# S9S_MB_2U (Grand Teton) — schematic netlist excerpt (pin names and nets, part order shuffled) for the footprints in the layout excerpt that follows; sources: Cadence DE-HDL packaged netlist, KiCad conversion of 03242023_DA0F0TMBIJ0_F0T_Motherboard_J_brd_V01_OCP.brd

C1213  Q_CAP  22UF 16V 20% X6S  pkg C0805  page 153 : A = P12V_OCP_SFF ; B = GND
H15  HOLE  EMPTY  pkg TH  page 311 : \1\ = NC
C763  Q_CAP_DIFFBUS  DIFF BUS_0.22UF 6.3V 20% X6S  pkg C0201  page 176 : \1\ = P5E_CPU1_PE2_TX_C_DP<5> ; \2\ = P5E_CPU1_PE2_TX_DP<5>
R3711  Q_RES  33.2 1% CHIP  pkg 0402LF  page 233 : A = SMB_VR_SENSOR_3V3AUX_SCL ; B = SMB_VR_SENSOR_3V3AUX_SCL_R

(kicad_pcb
	(version 20260206)
	(generator "pcbnew")
	(generator_version "10.0")
	(general
		(thickness 1.6)
		(legacy_teardrops no)
	)
	(paper "A4")
	(title_block
		(title "03242023_DA0F0TMBIJ0_F0T_Motherboard_J_brd_V01_OCP.brd")
		(comment 1 "Grand Teton / footprints 3624-3627 of 6105")
	)
	(layers
		(0 "F.Cu" signal "TOP")
		(4 "In1.Cu" signal "GND")
		(6 "In2.Cu" signal "IN1")
		(8 "In3.Cu" signal "GND1")
		(10 "In4.Cu" signal "IN2")
		(12 "In5.Cu" signal "GND2")
		(14 "In6.Cu" signal "IN3")
		(16 "In7.Cu" signal "GND3")
		(18 "In8.Cu" signal "VCC")
		(20 "In9.Cu" signal "VCC1")
		(22 "In10.Cu" signal "GND4")
		(24 "In11.Cu" signal "IN4")
		(26 "In12.Cu" signal "GND5")
		(28 "In13.Cu" signal "IN5")
		(30 "In14.Cu" signal "GND6")
		(32 "In15.Cu" signal "IN6")
		(34 "In16.Cu" signal "GND7")
		(2 "B.Cu" signal "BOTTOM")
		(9 "F.Adhes" user "F.Adhesive")
		(11 "B.Adhes" user "B.Adhesive")
		(13 "F.Paste" user "Package Geometry/Pastemask Top")
		(15 "B.Paste" user "Package Geometry/Pastemask Bottom")
		(5 "F.SilkS" user "Ref Des/Silkscreen Top")
		(7 "B.SilkS" user "Ref Des/Silkscreen Bottom")
		(1 "F.Mask" user "Board Geometry/Soldermask Top")
		(3 "B.Mask" user "Board Geometry/Soldermask Bottom")
		(17 "Dwgs.User" user "User.Drawings")
		(19 "Cmts.User" user "User.Comments")
		(21 "Eco1.User" user "User.Eco1")
		(23 "Eco2.User" user "User.Eco2")
		(25 "Edge.Cuts" user "Board Geometry/Outline")
		(27 "Margin" user)
		(31 "F.CrtYd" user "Package Geometry/Place Bound Top")
		(29 "B.CrtYd" user "Package Geometry/Place Bound Bottom")
		(35 "F.Fab" user "Ref Des/Assembly Top")
		(33 "B.Fab" user "Ref Des/Assembly Bottom")
	)
	(footprint ""
		(layer "F.Cu")
		(at 68.085716 -113.72469 180)
		(property "Reference" "R3711"
			(at 0 0 180)
			(layer "F.SilkS")
			(hide yes)
			(effects
				(font
					(size 1.27 1.27)
				)
			)
		)
		(property "Value" ""
			(at 0 0 180)
			(layer "F.Fab")
			(effects
				(font
					(size 1.27 1.27)
				)
			)
		)
		(duplicate_pad_numbers_are_jumpers no)
		(fp_line
			(start 0.7874 0.4064)
			(end -0.7874 0.4064)
			(stroke
				(width 0.1524)
				(type default)
			)
			(layer "F.SilkS")
		)
		(fp_line
			(start 0.7874 -0.4064)
			(end 0.7874 0.4064)
			(stroke
				(width 0.1524)
				(type default)
			)
			(layer "F.SilkS")
		)
		(fp_line
			(start -0.7874 0.4064)
			(end -0.7874 -0.4064)
			(stroke
				(width 0.1524)
				(type default)
			)
			(layer "F.SilkS")
		)
		(fp_line
			(start -0.7874 -0.4064)
			(end 0.7874 -0.4064)
			(stroke
				(width 0.1524)
				(type default)
			)
			(layer "F.SilkS")
		)
		(fp_line
			(start 0.67945 0.3048)
			(end 0.120396 0.3048)
			(stroke
				(width 0.1)
				(type default)
			)
			(layer "F.Fab")
		)
		(fp_line
			(start 0.67945 -0.3048)
			(end 0.67945 0.3048)
			(stroke
				(width 0.1)
				(type default)
			)
			(layer "F.Fab")
		)
		(fp_line
			(start 0.12065 -0.2794)
			(end 0.12065 -0.3048)
			(stroke
				(width 0.1)
				(type default)
			)
			(layer "F.Fab")
		)
		(fp_line
			(start 0.12065 -0.3048)
			(end 0.67945 -0.3048)
			(stroke
				(width 0.1)
				(type default)
			)
			(layer "F.Fab")
		)
		(fp_line
			(start 0.120396 0.3048)
			(end 0.120396 0.2794)
			(stroke
				(width 0.1)
				(type default)
			)
			(layer "F.Fab")
		)
		(fp_line
			(start 0.120396 0.2794)
			(end -0.12065 0.2794)
			(stroke
				(width 0.1)
				(type default)
			)
			(layer "F.Fab")
		)
		(fp_line
			(start -0.12065 0.3048)
			(end -0.67945 0.3048)
			(stroke
				(width 0.1)
				(type default)
			)
			(layer "F.Fab")
		)
		(fp_line
			(start -0.12065 0.2794)
			(end -0.12065 0.3048)
			(stroke
				(width 0.1)
				(type default)
			)
			(layer "F.Fab")
		)
		(fp_line
			(start -0.12065 -0.2794)
			(end 0.12065 -0.2794)
			(stroke
				(width 0.1)
				(type default)
			)
			(layer "F.Fab")
		)
		(fp_line
			(start -0.12065 -0.305054)
			(end -0.12065 -0.2794)
			(stroke
				(width 0.1)
				(type default)
			)
			(layer "F.Fab")
		)
		(fp_line
			(start -0.67945 0.3048)
			(end -0.67945 -0.305054)
			(stroke
				(width 0.1)
				(type default)
			)
			(layer "F.Fab")
		)
		(fp_line
			(start -0.67945 -0.305054)
			(end -0.12065 -0.305054)
			(stroke
				(width 0.1)
				(type default)
			)
			(layer "F.Fab")
		)
		(pad "1" smd circle
			(at -0.40005 0 180)
			(size 0 0)
			(layers "F.Cu" "F.Mask" "F.Paste")
			(net "SMB_VR_SENSOR_3V3AUX_SCL")
		)
		(pad "2" smd circle
			(at 0.40005 0 180)
			(size 0 0)
			(layers "F.Cu" "F.Mask" "F.Paste")
			(net "SMB_VR_SENSOR_3V3AUX_SCL_R")
		)
	)
	(footprint ""
		(layer "F.Cu")
		(at 150.761954 -402.371052 -90)
		(property "Reference" "C763"
			(at 0 0 270)
			(layer "F.SilkS")
			(hide yes)
			(effects
				(font
					(size 1.27 1.27)
				)
			)
		)
		(property "Value" ""
			(at 0 0 270)
			(layer "F.Fab")
			(effects
				(font
					(size 1.27 1.27)
				)
			)
		)
		(duplicate_pad_numbers_are_jumpers no)
		(fp_line
			(start -0.299974 0.150114)
			(end -0.299974 -0.150114)
			(stroke
				(width 0.1)
				(type default)
			)
			(layer "F.Fab")
		)
		(fp_line
			(start 0.299974 0.150114)
			(end -0.299974 0.150114)
			(stroke
				(width 0.1)
				(type default)
			)
			(layer "F.Fab")
		)
		(fp_line
			(start -0.299974 -0.150114)
			(end 0.299974 -0.150114)
			(stroke
				(width 0.1)
				(type default)
			)
			(layer "F.Fab")
		)
		(fp_line
			(start 0.299974 -0.150114)
			(end 0.299974 0.150114)
			(stroke
				(width 0.1)
				(type default)
			)
			(layer "F.Fab")
		)
		(pad "1" smd rect
			(at -0.2667 0 270)
			(size 0.3048 0.381)
			(layers "F.Cu" "F.Mask" "F.Paste")
			(net "P5E_CPU1_PE2_TX_C_DP<5>")
		)
		(pad "2" smd rect
			(at 0.2667 0 270)
			(size 0.3048 0.381)
			(layers "F.Cu" "F.Mask" "F.Paste")
			(net "P5E_CPU1_PE2_TX_DP<5>")
		)
	)
	(footprint ""
		(layer "F.Cu")
		(at 440.137804 -18.27022 180)
		(property "Reference" "C1213"
			(at 0 0 180)
			(layer "F.SilkS")
			(hide yes)
			(effects
				(font
					(size 1.27 1.27)
				)
			)
		)
		(property "Value" ""
			(at 0 0 180)
			(layer "F.Fab")
			(effects
				(font
					(size 1.27 1.27)
				)
			)
		)
		(duplicate_pad_numbers_are_jumpers no)
		(fp_line
			(start 1.524 0.762)
			(end -1.524 0.762)
			(stroke
				(width 0.1524)
				(type default)
			)
			(layer "F.SilkS")
		)
		(fp_line
			(start 1.524 -0.762)
			(end 1.524 0.762)
			(stroke
				(width 0.1524)
				(type default)
			)
			(layer "F.SilkS")
		)
		(fp_line
			(start -1.524 0.762)
			(end -1.524 -0.762)
			(stroke
				(width 0.1524)
				(type default)
			)
			(layer "F.SilkS")
		)
		(fp_line
			(start -1.524 -0.762)
			(end 1.524 -0.762)
			(stroke
				(width 0.1524)
				(type default)
			)
			(layer "F.SilkS")
		)
		(fp_line
			(start 1.1049 0.724916)
			(end 1.1049 -0.724916)
			(stroke
				(width 0.1)
				(type default)
			)
			(layer "F.Fab")
		)
		(fp_line
			(start 1.1049 -0.724916)
			(end -1.1049 -0.724916)
			(stroke
				(width 0.1)
				(type default)
			)
			(layer "F.Fab")
		)
		(fp_line
			(start -1.1049 0.724916)
			(end 1.1049 0.724916)
			(stroke
				(width 0.1)
				(type default)
			)
			(layer "F.Fab")
		)
		(fp_line
			(start -1.1049 -0.724916)
			(end -1.1049 0.724916)
			(stroke
				(width 0.1)
				(type default)
			)
			(layer "F.Fab")
		)
		(pad "1" smd rect
			(at -0.889 0)
			(size 1.016 1.27)
			(layers "F.Cu" "F.Mask" "F.Paste")
			(net "P12V_OCP_SFF")
		)
		(pad "2" smd rect
			(at 0.889 0)
			(size 1.016 1.27)
			(layers "F.Cu" "F.Mask" "F.Paste")
			(net "GND")
		)
	)
	(footprint ""
		(layer "F.Cu")
		(at 338.38007 -297.514772)
		(property "Reference" "H15"
			(at -1.83007 -5.064506 0)
			(unlocked yes)
			(layer "F.SilkS")
			(effects
				(font
					(size 0.7874 0.5842)
					(thickness 0.1524)
				)
				(justify left)
			)
		)
		(property "Value" ""
			(at 0 0 0)
			(layer "F.Fab")
			(effects
				(font
					(size 1.27 1.27)
				)
			)
		)
		(duplicate_pad_numbers_are_jumpers no)
		(fp_circle
			(center 0 0)
			(end 2.5273 0)
			(stroke
				(width 0.1524)
				(type default)
			)
			(fill no)
			(layer "F.SilkS")
		)
		(fp_circle
			(center 0 0)
			(end 2.5273 0)
			(stroke
				(width 0.1524)
				(type default)
			)
			(fill no)
			(layer "B.SilkS")
		)
		(fp_circle
			(center 0 0)
			(end 2.5273 0)
			(stroke
				(width 0.1)
				(type default)
			)
			(fill no)
			(layer "B.Fab")
		)
		(fp_circle
			(center 0 0)
			(end 2.5273 0)
			(stroke
				(width 0.1)
				(type default)
			)
			(fill no)
			(layer "F.Fab")
		)
		(pad "" np_thru_hole circle
			(at 0 0)
			(size 3.429 3.429)
			(drill 3.429)
			(layers "*.Cu" "*.Mask")
			(clearance 0.381)
			(thermal_gap 0.381)
		)
	)
)
